# T6G (Grand Teton) — schematic netlist excerpt (pin names and nets, part order shuffled) for the footprints in the layout excerpt that follows; sources: Cadence DE-HDL packaged netlist, KiCad conversion of 04192023_DAF0TMB3IC0_F0TG_MB_C_brd_V02_OCP.brd

R28  Q_RES  0 5% CHIP  pkg 0402LF  page 28 : A = SMB_CPU0_2_R_SDA ; B = SMB_CPU0_2_SDA
R281  Q_RES  0 5% CHIP  pkg 0402LF  page 160 : A = SMB_CPU0_CPU1_APML_BUF2_SDA_R2 ; B = SMB_CPU0_CPU1_APML_SDA_R2
C477  Q_CAP  0.1UF 10V 10% X7S  pkg C0201  page 356 : A = P0V9_CPU1_RT3_2A ; B = GND

(kicad_pcb
	(version 20260206)
	(generator "pcbnew")
	(generator_version "10.0")
	(general
		(thickness 1.6)
		(legacy_teardrops no)
	)
	(paper "A4")
	(title_block
		(title "04192023_DAF0TMB3IC0_F0TG_MB_C_brd_V02_OCP.brd")
		(comment 1 "Grand Teton / footprints 7323-7325 of 8354")
	)
	(layers
		(0 "F.Cu" signal "TOP")
		(4 "In1.Cu" signal "GND")
		(6 "In2.Cu" signal "IN1")
		(8 "In3.Cu" signal "GND1")
		(10 "In4.Cu" signal "IN2")
		(12 "In5.Cu" signal "GND2")
		(14 "In6.Cu" signal "IN3")
		(16 "In7.Cu" signal "GND3")
		(18 "In8.Cu" signal "VCC")
		(20 "In9.Cu" signal "VCC1")
		(22 "In10.Cu" signal "GND4")
		(24 "In11.Cu" signal "IN4")
		(26 "In12.Cu" signal "GND5")
		(28 "In13.Cu" signal "IN5")
		(30 "In14.Cu" signal "GND6")
		(32 "In15.Cu" signal "IN6")
		(34 "In16.Cu" signal "GND7")
		(2 "B.Cu" signal "BOTTOM")
		(9 "F.Adhes" user "F.Adhesive")
		(11 "B.Adhes" user "B.Adhesive")
		(13 "F.Paste" user "Package Geometry/Pastemask Top")
		(15 "B.Paste" user "Package Geometry/Pastemask Bottom")
		(5 "F.SilkS" user "Ref Des/Silkscreen Top")
		(7 "B.SilkS" user "Ref Des/Silkscreen Bottom")
		(1 "F.Mask" user "Board Geometry/Soldermask Top")
		(3 "B.Mask" user "Board Geometry/Soldermask Bottom")
		(17 "Dwgs.User" user "User.Drawings")
		(19 "Cmts.User" user "User.Comments")
		(21 "Eco1.User" user "User.Eco1")
		(23 "Eco2.User" user "User.Eco2")
		(25 "Edge.Cuts" user "Board Geometry/Outline")
		(27 "Margin" user)
		(31 "F.CrtYd" user "Package Geometry/Place Bound Top")
		(29 "B.CrtYd" user "Package Geometry/Place Bound Bottom")
		(35 "F.Fab" user "Ref Des/Assembly Top")
		(33 "B.Fab" user "Ref Des/Assembly Bottom")
	)
	(footprint ""
		(layer "B.Cu")
		(at 313.734958 -201.926952 90)
		(property "Reference" "R28"
			(at 0 0 90)
			(layer "B.SilkS")
			(hide yes)
			(effects
				(font
					(size 1.27 1.27)
				)
				(justify mirror)
			)
		)
		(property "Value" ""
			(at 0 0 90)
			(layer "B.Fab")
			(effects
				(font
					(size 1.27 1.27)
				)
				(justify mirror)
			)
		)
		(duplicate_pad_numbers_are_jumpers no)
		(fp_line
			(start 0.7874 -0.4064)
			(end -0.7874 -0.4064)
			(stroke
				(width 0.1524)
				(type default)
			)
			(layer "B.SilkS")
		)
		(fp_line
			(start -0.7874 -0.4064)
			(end -0.7874 0.4064)
			(stroke
				(width 0.1524)
				(type default)
			)
			(layer "B.SilkS")
		)
		(fp_line
			(start 0.7874 0.4064)
			(end 0.7874 -0.4064)
			(stroke
				(width 0.1524)
				(type default)
			)
			(layer "B.SilkS")
		)
		(fp_line
			(start -0.7874 0.4064)
			(end 0.7874 0.4064)
			(stroke
				(width 0.1524)
				(type default)
			)
			(layer "B.SilkS")
		)
		(fp_line
			(start 0.67945 -0.305054)
			(end 0.12065 -0.305054)
			(stroke
				(width 0.1)
				(type default)
			)
			(layer "B.Fab")
		)
		(fp_line
			(start 0.12065 -0.305054)
			(end 0.12065 -0.2794)
			(stroke
				(width 0.1)
				(type default)
			)
			(layer "B.Fab")
		)
		(fp_line
			(start -0.12065 -0.3048)
			(end -0.67945 -0.3048)
			(stroke
				(width 0.1)
				(type default)
			)
			(layer "B.Fab")
		)
		(fp_line
			(start -0.67945 -0.3048)
			(end -0.67945 0.3048)
			(stroke
				(width 0.1)
				(type default)
			)
			(layer "B.Fab")
		)
		(fp_line
			(start 0.12065 -0.2794)
			(end -0.12065 -0.2794)
			(stroke
				(width 0.1)
				(type default)
			)
			(layer "B.Fab")
		)
		(fp_line
			(start -0.12065 -0.2794)
			(end -0.12065 -0.3048)
			(stroke
				(width 0.1)
				(type default)
			)
			(layer "B.Fab")
		)
		(fp_line
			(start 0.12065 0.2794)
			(end 0.12065 0.3048)
			(stroke
				(width 0.1)
				(type default)
			)
			(layer "B.Fab")
		)
		(fp_line
			(start -0.120396 0.2794)
			(end 0.12065 0.2794)
			(stroke
				(width 0.1)
				(type default)
			)
			(layer "B.Fab")
		)
		(fp_line
			(start 0.67945 0.3048)
			(end 0.67945 -0.305054)
			(stroke
				(width 0.1)
				(type default)
			)
			(layer "B.Fab")
		)
		(fp_line
			(start 0.12065 0.3048)
			(end 0.67945 0.3048)
			(stroke
				(width 0.1)
				(type default)
			)
			(layer "B.Fab")
		)
		(fp_line
			(start -0.120396 0.3048)
			(end -0.120396 0.2794)
			(stroke
				(width 0.1)
				(type default)
			)
			(layer "B.Fab")
		)
		(fp_line
			(start -0.67945 0.3048)
			(end -0.120396 0.3048)
			(stroke
				(width 0.1)
				(type default)
			)
			(layer "B.Fab")
		)
		(pad "1" smd circle
			(at 0.40005 0 270)
			(size 0 0)
			(layers "B.Cu" "B.Mask" "B.Paste")
			(net "SMB_CPU0_2_R_SDA")
		)
		(pad "2" smd circle
			(at -0.40005 0 270)
			(size 0 0)
			(layers "B.Cu" "B.Mask" "B.Paste")
			(net "SMB_CPU0_2_SDA")
		)
	)
	(footprint ""
		(layer "B.Cu")
		(at 234.286298 -213.258654 180)
		(property "Reference" "R281"
			(at 0 0 0)
			(layer "B.SilkS")
			(hide yes)
			(effects
				(font
					(size 1.27 1.27)
				)
				(justify mirror)
			)
		)
		(property "Value" ""
			(at 0 0 0)
			(layer "B.Fab")
			(effects
				(font
					(size 1.27 1.27)
				)
				(justify mirror)
			)
		)
		(duplicate_pad_numbers_are_jumpers no)
		(fp_line
			(start 0.7874 0.4064)
			(end 0.7874 -0.4064)
			(stroke
				(width 0.1524)
				(type default)
			)
			(layer "B.SilkS")
		)
		(fp_line
			(start 0.7874 -0.4064)
			(end -0.7874 -0.4064)
			(stroke
				(width 0.1524)
				(type default)
			)
			(layer "B.SilkS")
		)
		(fp_line
			(start -0.7874 0.4064)
			(end 0.7874 0.4064)
			(stroke
				(width 0.1524)
				(type default)
			)
			(layer "B.SilkS")
		)
		(fp_line
			(start -0.7874 -0.4064)
			(end -0.7874 0.4064)
			(stroke
				(width 0.1524)
				(type default)
			)
			(layer "B.SilkS")
		)
		(fp_line
			(start 0.67945 0.3048)
			(end 0.67945 -0.305054)
			(stroke
				(width 0.1)
				(type default)
			)
			(layer "B.Fab")
		)
		(fp_line
			(start 0.67945 -0.305054)
			(end 0.12065 -0.305054)
			(stroke
				(width 0.1)
				(type default)
			)
			(layer "B.Fab")
		)
		(fp_line
			(start 0.12065 0.3048)
			(end 0.67945 0.3048)
			(stroke
				(width 0.1)
				(type default)
			)
			(layer "B.Fab")
		)
		(fp_line
			(start 0.12065 0.2794)
			(end 0.12065 0.3048)
			(stroke
				(width 0.1)
				(type default)
			)
			(layer "B.Fab")
		)
		(fp_line
			(start 0.12065 -0.2794)
			(end -0.12065 -0.2794)
			(stroke
				(width 0.1)
				(type default)
			)
			(layer "B.Fab")
		)
		(fp_line
			(start 0.12065 -0.305054)
			(end 0.12065 -0.2794)
			(stroke
				(width 0.1)
				(type default)
			)
			(layer "B.Fab")
		)
		(fp_line
			(start -0.120396 0.3048)
			(end -0.120396 0.2794)
			(stroke
				(width 0.1)
				(type default)
			)
			(layer "B.Fab")
		)
		(fp_line
			(start -0.120396 0.2794)
			(end 0.12065 0.2794)
			(stroke
				(width 0.1)
				(type default)
			)
			(layer "B.Fab")
		)
		(fp_line
			(start -0.12065 -0.2794)
			(end -0.12065 -0.3048)
			(stroke
				(width 0.1)
				(type default)
			)
			(layer "B.Fab")
		)
		(fp_line
			(start -0.12065 -0.3048)
			(end -0.67945 -0.3048)
			(stroke
				(width 0.1)
				(type default)
			)
			(layer "B.Fab")
		)
		(fp_line
			(start -0.67945 0.3048)
			(end -0.120396 0.3048)
			(stroke
				(width 0.1)
				(type default)
			)
			(layer "B.Fab")
		)
		(fp_line
			(start -0.67945 -0.3048)
			(end -0.67945 0.3048)
			(stroke
				(width 0.1)
				(type default)
			)
			(layer "B.Fab")
		)
		(pad "1" smd rect
			(at 0.40005 0 180)
			(size 0.4572 0.508)
			(layers "B.Cu" "B.Mask" "B.Paste")
			(net "SMB_CPU0_CPU1_APML_BUF2_SDA_R2")
		)
		(pad "2" smd rect
			(at -0.40005 0 180)
			(size 0.4572 0.508)
			(layers "B.Cu" "B.Mask" "B.Paste")
			(net "SMB_CPU0_CPU1_APML_SDA_R2")
		)
	)
	(footprint ""
		(layer "B.Cu")
		(at 118.218458 -388.011162 -90)
		(property "Reference" "C477"
			(at 0 0 90)
			(layer "B.SilkS")
			(hide yes)
			(effects
				(font
					(size 1.27 1.27)
				)
				(justify mirror)
			)
		)
		(property "Value" ""
			(at 0 0 90)
			(layer "B.Fab")
			(effects
				(font
					(size 1.27 1.27)
				)
				(justify mirror)
			)
		)
		(duplicate_pad_numbers_are_jumpers no)
		(fp_line
			(start -0.299974 0.150114)
			(end 0.299974 0.150114)
			(stroke
				(width 0.1)
				(type default)
			)
			(layer "B.Fab")
		)
		(fp_line
			(start 0.299974 0.150114)
			(end 0.299974 -0.150114)
			(stroke
				(width 0.1)
				(type default)
			)
			(layer "B.Fab")
		)
		(fp_line
			(start -0.299974 -0.150114)
			(end -0.299974 0.150114)
			(stroke
				(width 0.1)
				(type default)
			)
			(layer "B.Fab")
		)
		(fp_line
			(start 0.299974 -0.150114)
			(end -0.299974 -0.150114)
			(stroke
				(width 0.1)
				(type default)
			)
			(layer "B.Fab")
		)
		(pad "1" smd rect
			(at 0.2667 0 90)
			(size 0.3048 0.381)
			(layers "B.Cu" "B.Mask" "B.Paste")
			(net "P0V9_CPU1_RT3_2A")
		)
		(pad "2" smd rect
			(at -0.2667 0 90)
			(size 0.3048 0.381)
			(layers "B.Cu" "B.Mask" "B.Paste")
			(net "GND")
		)
	)
)
